FILE_TYPE = MACRO_DRAWING;
SET COLOR_WIRE YELLOW;
SET COLOR_PROP ORANGE;
SET COLOR_DOT WHITE;
SET COLOR_ARC YELLOW;
SET COLOR_BODY GREEN;
SET COLOR_NOTE PURPLE;
SET PROP_DISPLAY VALUE;
SET PAGE_NUMBER P522;
FORCEADD OFFPAGE_OUT..1
(-4250 3100);
FORCEPROP 2 LAST $XR0 10D5< 
J 0
(-4195 3100);
DISPLAY 0.638298 (-4195 3100);
PAINT MONO (-4195 3100);
FORCEPROP 2 LAST CDS_LIB cls
J 0
(-4250 3100);
DISPLAY INVISIBLE (-4250 3100);
FORCEPROP 1 LAST CDS_LMAN_SYM_OUTLINE -50,50,50,-50
J 0
(-4250 3100);
DISPLAY 0.468085 (-4250 3100);
PAINT GREEN (-4250 3100);
DISPLAY INVISIBLE (-4250 3100);
FORCEPROP 1 LAST BODY_TYPE COMMENT
J 0
(-4240 3235);
DISPLAY 0.808511 (-4240 3235);
PAINT GREEN (-4240 3235);
DISPLAY INVISIBLE (-4240 3235);
FORCEPROP 1 LAST OFFPAGE TRUE
J 0
(-4240 3155);
DISPLAY 0.808511 (-4240 3155);
PAINT GREEN (-4240 3155);
DISPLAY INVISIBLE (-4240 3155);
FORCEPROP 2 LAST PATH I11
J 0
(-4200 3200);
DISPLAY 1.021277 (-4200 3200);
DISPLAY INVISIBLE (-4200 3200);
FORCEADD OFFPAGE_OUT..1
(-4250 3000);
FORCEPROP 2 LAST $XR0 10D5< 
J 0
(-4195 3000);
DISPLAY 0.638298 (-4195 3000);
PAINT MONO (-4195 3000);
FORCEPROP 2 LAST CDS_LIB cls
J 0
(-4250 3000);
DISPLAY INVISIBLE (-4250 3000);
FORCEPROP 1 LAST CDS_LMAN_SYM_OUTLINE -50,50,50,-50
J 0
(-4250 3000);
DISPLAY 0.468085 (-4250 3000);
PAINT GREEN (-4250 3000);
DISPLAY INVISIBLE (-4250 3000);
FORCEPROP 1 LAST BODY_TYPE COMMENT
J 0
(-4240 3135);
DISPLAY 0.808511 (-4240 3135);
PAINT GREEN (-4240 3135);
DISPLAY INVISIBLE (-4240 3135);
FORCEPROP 1 LAST OFFPAGE TRUE
J 0
(-4240 3055);
DISPLAY 0.808511 (-4240 3055);
PAINT GREEN (-4240 3055);
DISPLAY INVISIBLE (-4240 3055);
FORCEPROP 2 LAST PATH I12
J 0
(-4200 3100);
DISPLAY 1.021277 (-4200 3100);
DISPLAY INVISIBLE (-4200 3100);
FORCEADD OFFPAGE_OUT..1
(-4100 6650);
FORCEPROP 2 LAST $XR0 13G12< 
J 0
(-4045 6650);
DISPLAY 0.638298 (-4045 6650);
PAINT MONO (-4045 6650);
FORCEPROP 2 LAST CDS_LIB cls
J 0
(-4100 6650);
DISPLAY INVISIBLE (-4100 6650);
FORCEPROP 1 LAST CDS_LMAN_SYM_OUTLINE -50,50,50,-50
J 0
(-4100 6650);
DISPLAY 0.468085 (-4100 6650);
PAINT GREEN (-4100 6650);
DISPLAY INVISIBLE (-4100 6650);
FORCEPROP 1 LAST BODY_TYPE COMMENT
J 0
(-4090 6785);
DISPLAY 0.808511 (-4090 6785);
PAINT GREEN (-4090 6785);
DISPLAY INVISIBLE (-4090 6785);
FORCEPROP 1 LAST OFFPAGE TRUE
J 0
(-4090 6705);
DISPLAY 0.808511 (-4090 6705);
PAINT GREEN (-4090 6705);
DISPLAY INVISIBLE (-4090 6705);
FORCEPROP 2 LAST PATH I13
J 0
(-4050 6750);
DISPLAY 1.021277 (-4050 6750);
DISPLAY INVISIBLE (-4050 6750);
FORCEADD OFFPAGE_OUT..1
(-4100 6550);
FORCEPROP 2 LAST $XR0 13G12< 
J 0
(-4045 6550);
DISPLAY 0.638298 (-4045 6550);
PAINT MONO (-4045 6550);
FORCEPROP 2 LAST CDS_LIB cls
J 0
(-4100 6550);
DISPLAY INVISIBLE (-4100 6550);
FORCEPROP 1 LAST CDS_LMAN_SYM_OUTLINE -50,50,50,-50
J 0
(-4100 6550);
DISPLAY 0.468085 (-4100 6550);
PAINT GREEN (-4100 6550);
DISPLAY INVISIBLE (-4100 6550);
FORCEPROP 1 LAST BODY_TYPE COMMENT
J 0
(-4090 6685);
DISPLAY 0.808511 (-4090 6685);
PAINT GREEN (-4090 6685);
DISPLAY INVISIBLE (-4090 6685);
FORCEPROP 1 LAST OFFPAGE TRUE
J 0
(-4090 6605);
DISPLAY 0.808511 (-4090 6605);
PAINT GREEN (-4090 6605);
DISPLAY INVISIBLE (-4090 6605);
FORCEPROP 2 LAST PATH I14
J 0
(-4050 6650);
DISPLAY 1.021277 (-4050 6650);
DISPLAY INVISIBLE (-4050 6650);
FORCEADD CAPACITOR..1
(-6200 3000);
FORCEPROP 1 LAST $LOCATION C254
J 2
(-6350 3000);
DISPLAY 1.212766 (-6350 3000);
PAINT GREEN (-6350 3000);
FORCEPROP 0 LAST CDS_LOCATION C254
J 0
(-5950 3100);
DISPLAY 1.021277 (-5950 3100);
DISPLAY INVISIBLE (-5950 3100);
FORCEPROP 0 LAST $SEC 1
J 0
(-5950 3100);
DISPLAY 0.680851 (-5950 3100);
PAINT MONO (-5950 3100);
DISPLAY INVISIBLE (-5950 3100);
FORCEPROP 0 LAST CDS_SEC 1
J 0
(-5950 3100);
DISPLAY 1.021277 (-5950 3100);
DISPLAY INVISIBLE (-5950 3100);
FORCEPROP 0 LASTPIN (-6300 3000) $PN 1
J 2
(-6310 3010);
DISPLAY 0.680851 (-6310 3010);
PAINT MONO (-6310 3010);
FORCEPROP 0 LASTPIN (-6050 3000) $PN 2
J 0
(-6040 3010);
DISPLAY 0.680851 (-6040 3010);
PAINT MONO (-6040 3010);
FORCEPROP 0 LAST PACKAGE 0402
J 0
(-6250 2850);
DISPLAY 1.021277 (-6250 2850);
FORCEPROP 0 LAST VOLTAGE 10V
J 0
(-6000 2850);
DISPLAY 1.021277 (-6000 2850);
FORCEPROP 1 LAST VALUE 0.1UF
J 0
(-5950 3000);
DISPLAY 1.212766 (-5950 3000);
PAINT GREEN (-5950 3000);
FORCEPROP 2 LAST CDS_LIB passive
J 0
(-6200 3000);
DISPLAY INVISIBLE (-6200 3000);
FORCEPROP 1 LAST CDS_LMAN_SYM_OUTLINE 0,50,50,-50
J 0
(-6200 3000);
DISPLAY 0.468085 (-6200 3000);
PAINT GREEN (-6200 3000);
DISPLAY INVISIBLE (-6200 3000);
FORCEPROP 1 LAST CLS_PN G105-0B104-CK
J 2
(-6250 3100);
DISPLAY 1.212766 (-6250 3100);
PAINT GREEN (-6250 3100);
DISPLAY INVISIBLE (-6250 3100);
FORCEPROP 1 LAST TOLERANCE 10%
J 2
(-6300 3100);
DISPLAY 1.212766 (-6300 3100);
PAINT GREEN (-6300 3100);
DISPLAY INVISIBLE (-6300 3100);
FORCEPROP 1 LAST PATH I142
J 2
(-6250 3100);
DISPLAY 1.212766 (-6250 3100);
PAINT GREEN (-6250 3100);
DISPLAY INVISIBLE (-6250 3100);
FORCEADD CAPACITOR..1
(-6200 3100);
FORCEPROP 1 LAST $LOCATION C253
J 2
(-6350 3100);
DISPLAY 1.212766 (-6350 3100);
PAINT GREEN (-6350 3100);
FORCEPROP 0 LAST CDS_LOCATION C253
J 0
(-5950 3200);
DISPLAY 1.021277 (-5950 3200);
DISPLAY INVISIBLE (-5950 3200);
FORCEPROP 0 LAST $SEC 1
J 0
(-5950 3200);
DISPLAY 0.680851 (-5950 3200);
PAINT MONO (-5950 3200);
DISPLAY INVISIBLE (-5950 3200);
FORCEPROP 0 LAST CDS_SEC 1
J 0
(-5950 3200);
DISPLAY 1.021277 (-5950 3200);
DISPLAY INVISIBLE (-5950 3200);
FORCEPROP 0 LASTPIN (-6300 3100) $PN 1
J 2
(-6310 3110);
DISPLAY 0.680851 (-6310 3110);
PAINT MONO (-6310 3110);
FORCEPROP 0 LASTPIN (-6050 3100) $PN 2
J 0
(-6040 3110);
DISPLAY 0.680851 (-6040 3110);
PAINT MONO (-6040 3110);
FORCEPROP 1 LAST VALUE 0.1UF
J 0
(-5950 3100);
DISPLAY 1.212766 (-5950 3100);
PAINT GREEN (-5950 3100);
FORCEPROP 0 LAST PACKAGE 0402
J 0
(-6250 3200);
DISPLAY 1.021277 (-6250 3200);
FORCEPROP 0 LAST VOLTAGE 10V
J 0
(-6000 3200);
DISPLAY 1.021277 (-6000 3200);
FORCEPROP 2 LAST CDS_LIB passive
J 0
(-6200 3100);
DISPLAY INVISIBLE (-6200 3100);
FORCEPROP 1 LAST CDS_LMAN_SYM_OUTLINE 0,50,50,-50
J 0
(-6200 3100);
DISPLAY 0.468085 (-6200 3100);
PAINT GREEN (-6200 3100);
DISPLAY INVISIBLE (-6200 3100);
FORCEPROP 1 LAST CLS_PN G105-0B104-CK
J 2
(-6250 3200);
DISPLAY 1.212766 (-6250 3200);
PAINT GREEN (-6250 3200);
DISPLAY INVISIBLE (-6250 3200);
FORCEPROP 1 LAST TOLERANCE 10%
J 2
(-6300 3200);
DISPLAY 1.212766 (-6300 3200);
PAINT GREEN (-6300 3200);
DISPLAY INVISIBLE (-6300 3200);
FORCEPROP 1 LAST PATH I143
J 2
(-6250 3200);
DISPLAY 1.212766 (-6250 3200);
PAINT GREEN (-6250 3200);
DISPLAY INVISIBLE (-6250 3200);
FORCEADD OSC6P_V2..1
(-8750 6750);
FORCEPROP 1 LAST $LOCATION Y3
J 0
(-8700 6850);
DISPLAY 1.212766 (-8700 6850);
PAINT GREEN (-8700 6850);
FORCEPROP 0 LAST CDS_LOCATION Y3
J 0
(-8700 7050);
DISPLAY 1.021277 (-8700 7050);
DISPLAY INVISIBLE (-8700 7050);
FORCEPROP 0 LAST $SEC 1
J 0
(-8700 7050);
DISPLAY 0.680851 (-8700 7050);
PAINT MONO (-8700 7050);
DISPLAY INVISIBLE (-8700 7050);
FORCEPROP 0 LAST CDS_SEC 1
J 0
(-8700 7050);
DISPLAY 1.021277 (-8700 7050);
DISPLAY INVISIBLE (-8700 7050);
FORCEPROP 0 LASTPIN (-8050 6350) $PN 3
J 0
(-8040 6360);
DISPLAY 0.680851 (-8040 6360);
PAINT MONO (-8040 6360);
FORCEPROP 0 LASTPIN (-8850 6350) $PN 2
J 2
(-8860 6360);
DISPLAY 0.680851 (-8860 6360);
PAINT MONO (-8860 6360);
FORCEPROP 0 LASTPIN (-8850 6450) $PN 1
J 2
(-8860 6460);
DISPLAY 0.680851 (-8860 6460);
PAINT MONO (-8860 6460);
FORCEPROP 0 LASTPIN (-8050 6550) $PN 5
J 0
(-8040 6560);
DISPLAY 0.680851 (-8040 6560);
PAINT MONO (-8040 6560);
FORCEPROP 0 LASTPIN (-8050 6650) $PN 4
J 0
(-8040 6660);
DISPLAY 0.680851 (-8040 6660);
PAINT MONO (-8040 6660);
FORCEPROP 0 LASTPIN (-8850 6650) $PN 6
J 2
(-8860 6660);
DISPLAY 0.680851 (-8860 6660);
PAINT MONO (-8860 6660);
FORCEPROP 0 LAST PART_NUMBER LMK62A2-200M00SIAR
J 0
(-8700 7050);
DISPLAY 1.021277 (-8700 7050);
FORCEPROP 1 LAST CLS_PN A130-00003-AW
J 0
(-8700 6950);
DISPLAY 1.212766 (-8700 6950);
PAINT GREEN (-8700 6950);
FORCEPROP 2 LAST CDS_LIB clock
J 0
(-8750 6750);
DISPLAY INVISIBLE (-8750 6750);
FORCEPROP 1 LAST CDS_LMAN_SYM_OUTLINE 0,0,600,-500
J 0
(-8750 6750);
DISPLAY 0.468085 (-8750 6750);
PAINT GREEN (-8750 6750);
DISPLAY INVISIBLE (-8750 6750);
FORCEPROP 1 LAST PATH I144
J 0
(-8700 6800);
DISPLAY 1.212766 (-8700 6800);
PAINT GREEN (-8700 6800);
DISPLAY INVISIBLE (-8700 6800);
FORCEADD OSC6P_V2..1
(-8750 3200);
FORCEPROP 1 LAST $LOCATION Y4
J 0
(-8700 3300);
DISPLAY 1.212766 (-8700 3300);
PAINT GREEN (-8700 3300);
FORCEPROP 0 LAST CDS_LOCATION Y4
J 0
(-8700 3500);
DISPLAY 1.021277 (-8700 3500);
DISPLAY INVISIBLE (-8700 3500);
FORCEPROP 0 LAST $SEC 1
J 0
(-8700 3500);
DISPLAY 0.680851 (-8700 3500);
PAINT MONO (-8700 3500);
DISPLAY INVISIBLE (-8700 3500);
FORCEPROP 0 LAST CDS_SEC 1
J 0
(-8700 3500);
DISPLAY 1.021277 (-8700 3500);
DISPLAY INVISIBLE (-8700 3500);
FORCEPROP 0 LASTPIN (-8050 2800) $PN 3
J 0
(-8040 2810);
DISPLAY 0.680851 (-8040 2810);
PAINT MONO (-8040 2810);
FORCEPROP 0 LASTPIN (-8850 2800) $PN 2
J 2
(-8860 2810);
DISPLAY 0.680851 (-8860 2810);
PAINT MONO (-8860 2810);
FORCEPROP 0 LASTPIN (-8850 2900) $PN 1
J 2
(-8860 2910);
DISPLAY 0.680851 (-8860 2910);
PAINT MONO (-8860 2910);
FORCEPROP 0 LASTPIN (-8050 3000) $PN 5
J 0
(-8040 3010);
DISPLAY 0.680851 (-8040 3010);
PAINT MONO (-8040 3010);
FORCEPROP 0 LASTPIN (-8050 3100) $PN 4
J 0
(-8040 3110);
DISPLAY 0.680851 (-8040 3110);
PAINT MONO (-8040 3110);
FORCEPROP 0 LASTPIN (-8850 3100) $PN 6
J 2
(-8860 3110);
DISPLAY 0.680851 (-8860 3110);
PAINT MONO (-8860 3110);
FORCEPROP 1 LAST CLS_PN A130-00004-AW
J 0
(-8700 3400);
DISPLAY 1.212766 (-8700 3400);
PAINT GREEN (-8700 3400);
FORCEPROP 0 LAST PART_NUMBER LMK61A2-125M00SIAR
J 0
(-8700 3500);
DISPLAY 1.021277 (-8700 3500);
FORCEPROP 2 LAST CDS_LIB clock
J 0
(-8750 3200);
DISPLAY INVISIBLE (-8750 3200);
FORCEPROP 1 LAST CDS_LMAN_SYM_OUTLINE 0,0,600,-500
J 0
(-8750 3200);
DISPLAY 0.468085 (-8750 3200);
PAINT GREEN (-8750 3200);
DISPLAY INVISIBLE (-8750 3200);
FORCEPROP 1 LAST PATH I145
J 0
(-8700 3250);
DISPLAY 1.212766 (-8700 3250);
PAINT GREEN (-8700 3250);
DISPLAY INVISIBLE (-8700 3250);
FORCEADD FERRITEBEAD..1
R 2
(-11050 6700);
FORCEPROP 1 LAST $LOCATION L14
J 0
(-11550 6700);
DISPLAY 1.212766 (-11550 6700);
PAINT GREEN (-11550 6700);
FORCEPROP 0 LAST CDS_LOCATION L14
J 0
(-10850 6850);
DISPLAY 1.021277 (-10850 6850);
DISPLAY INVISIBLE (-10850 6850);
FORCEPROP 0 LAST $SEC 1
J 0
(-10850 6850);
DISPLAY 0.680851 (-10850 6850);
PAINT MONO (-10850 6850);
DISPLAY INVISIBLE (-10850 6850);
FORCEPROP 0 LAST CDS_SEC 1
J 0
(-10850 6850);
DISPLAY 1.021277 (-10850 6850);
DISPLAY INVISIBLE (-10850 6850);
FORCEPROP 0 LASTPIN (-10950 6650) $PN 1
J 0
(-10940 6660);
DISPLAY 0.680851 (-10940 6660);
PAINT MONO (-10940 6660);
FORCEPROP 0 LASTPIN (-11350 6650) $PN 2
J 2
(-11360 6660);
DISPLAY 0.680851 (-11360 6660);
PAINT MONO (-11360 6660);
FORCEPROP 0 LAST PACKAGE 0603
J 0
(-11250 6750);
DISPLAY 1.021277 (-11250 6750);
FORCEPROP 1 LAST VALUE 600OHM
J 2
(-10650 6750);
DISPLAY 1.212766 (-10650 6750);
PAINT GREEN (-10650 6750);
FORCEPROP 2 LAST DCR 1300MA 0.15OHM
J 2
(-10800 6550);
FORCEPROP 1 LAST TOLERANCE 25%
J 2
(-10950 6750);
DISPLAY 1.212766 (-10950 6750);
PAINT GREEN (-10950 6750);
DISPLAY INVISIBLE (-10950 6750);
FORCEPROP 1 LAST PATH I146
J 0
(-11000 6750);
DISPLAY 1.212766 (-11000 6750);
PAINT GREEN (-11000 6750);
DISPLAY INVISIBLE (-11000 6750);
FORCEPROP 1 LAST CLS_PN G191-10097-01
J 0
(-11000 6750);
DISPLAY 1.212766 (-11000 6750);
PAINT GREEN (-11000 6750);
DISPLAY INVISIBLE (-11000 6750);
FORCEPROP 2 LAST CDS_LIB passive
J 0
(-11050 6700);
DISPLAY INVISIBLE (-11050 6700);
FORCEPROP 1 LAST CDS_LMAN_SYM_OUTLINE 0,0,200,-100
J 2
(-11050 6700);
DISPLAY 0.468085 (-11050 6700);
PAINT GREEN (-11050 6700);
DISPLAY INVISIBLE (-11050 6700);
FORCEADD CAPACITOR..2
R 2
(-10200 6350);
FORCEPROP 1 LAST $LOCATION C248
J 2
(-10250 6200);
DISPLAY 1.212766 (-10250 6200);
PAINT GREEN (-10250 6200);
FORCEPROP 0 LAST CDS_LOCATION C248
J 0
(-10250 6480);
DISPLAY 1.021277 (-10250 6480);
DISPLAY INVISIBLE (-10250 6480);
FORCEPROP 0 LAST $SEC 1
J 0
(-10250 6480);
DISPLAY 0.680851 (-10250 6480);
PAINT MONO (-10250 6480);
DISPLAY INVISIBLE (-10250 6480);
FORCEPROP 0 LAST CDS_SEC 1
J 0
(-10250 6480);
DISPLAY 1.021277 (-10250 6480);
DISPLAY INVISIBLE (-10250 6480);
FORCEPROP 0 LASTPIN (-10200 6450) $PN 1
R 1
J 0
(-10210 6460);
DISPLAY 0.680851 (-10210 6460);
PAINT MONO (-10210 6460);
FORCEPROP 0 LASTPIN (-10200 6200) $PN 2
R 1
J 2
(-10210 6190);
DISPLAY 0.680851 (-10210 6190);
PAINT MONO (-10210 6190);
FORCEPROP 1 LAST VALUE 0.1UF
J 2
(-10250 6400);
DISPLAY 1.212766 (-10250 6400);
PAINT GREEN (-10250 6400);
FORCEPROP 0 LAST VOLTAGE 25V
J 0
(-10450 6100);
DISPLAY 1.021277 (-10450 6100);
FORCEPROP 0 LAST PACKAGE 0402
J 0
(-10450 6300);
DISPLAY 1.021277 (-10450 6300);
FORCEPROP 1 LAST TOLERANCE 10%
J 2
(-10050 6450);
DISPLAY 1.212766 (-10050 6450);
PAINT GREEN (-10050 6450);
DISPLAY INVISIBLE (-10050 6450);
FORCEPROP 1 LAST CLS_PN G105-0B104-EK
J 2
(-10100 6400);
DISPLAY 1.212766 (-10100 6400);
PAINT GREEN (-10100 6400);
DISPLAY INVISIBLE (-10100 6400);
FORCEPROP 1 LAST CDS_LMAN_SYM_OUTLINE -50,0,50,-50
J 2
(-10200 6350);
DISPLAY 0.468085 (-10200 6350);
PAINT GREEN (-10200 6350);
DISPLAY INVISIBLE (-10200 6350);
FORCEPROP 2 LAST CDS_LIB passive
J 0
(-10200 6350);
DISPLAY INVISIBLE (-10200 6350);
FORCEPROP 1 LAST PATH I147
J 2
(-10100 6400);
DISPLAY 1.212766 (-10100 6400);
PAINT GREEN (-10100 6400);
DISPLAY INVISIBLE (-10100 6400);
FORCEADD RESISTOR..1
(-9400 6450);
FORCEPROP 1 LAST $LOCATION R235
J 2
(-9350 6500);
DISPLAY 1.212766 (-9350 6500);
PAINT GREEN (-9350 6500);
FORCEPROP 0 LAST CDS_LOCATION R235
J 0
(-9500 6600);
DISPLAY 1.021277 (-9500 6600);
DISPLAY INVISIBLE (-9500 6600);
FORCEPROP 0 LAST $SEC 1
J 0
(-9500 6600);
DISPLAY 0.680851 (-9500 6600);
PAINT MONO (-9500 6600);
DISPLAY INVISIBLE (-9500 6600);
FORCEPROP 0 LAST CDS_SEC 1
J 0
(-9500 6600);
DISPLAY 1.021277 (-9500 6600);
DISPLAY INVISIBLE (-9500 6600);
FORCEPROP 0 LASTPIN (-9500 6450) $PN 1
J 2
(-9510 6460);
DISPLAY 0.680851 (-9510 6460);
PAINT MONO (-9510 6460);
FORCEPROP 0 LASTPIN (-9250 6450) $PN 2
J 0
(-9240 6460);
DISPLAY 0.680851 (-9240 6460);
PAINT MONO (-9240 6460);
FORCEPROP 1 LAST VALUE 4.7KOHM
J 0
(-9550 6350);
DISPLAY 1.212766 (-9550 6350);
PAINT GREEN (-9550 6350);
FORCEPROP 0 LAST PACKAGE 0402
J 0
(-9300 6500);
DISPLAY 1.021277 (-9300 6500);
FORCEPROP 1 LAST PATH I149
J 0
(-9597 6555);
DISPLAY 1.212766 (-9597 6555);
PAINT GREEN (-9597 6555);
DISPLAY INVISIBLE (-9597 6555);
FORCEPROP 1 LAST TOLERANCE 1%
J 0
(-9597 6705);
DISPLAY 1.212766 (-9597 6705);
PAINT GREEN (-9597 6705);
DISPLAY INVISIBLE (-9597 6705);
FORCEPROP 2 LAST CDS_LIB passive
J 0
(-9400 6450);
DISPLAY INVISIBLE (-9400 6450);
FORCEPROP 1 LAST CDS_LMAN_SYM_OUTLINE -50,50,100,-50
J 0
(-9400 6450);
DISPLAY 0.468085 (-9400 6450);
PAINT GREEN (-9400 6450);
DISPLAY INVISIBLE (-9400 6450);
FORCEPROP 1 LAST CLS_PN G155-14701-01
J 0
(-9536 6650);
DISPLAY 1.212766 (-9536 6650);
PAINT GREEN (-9536 6650);
DISPLAY INVISIBLE (-9536 6650);
FORCEADD GND_SG..1
R 2
(-10150 5800);
FORCEPROP 3 LASTPIN (-10200 5850) SIG_NAME SG\g
J 0
(-10190 5860);
DISPLAY 0.659574 (-10190 5860);
PAINT MONO (-10190 5860);
DISPLAY INVISIBLE (-10190 5860);
FORCEPROP 1 LAST HDL_POWER SG
J 1
(-10205 5705);
DISPLAY 0.808511 (-10205 5705);
PAINT GREEN (-10205 5705);
FORCEPROP 1 LAST CDS_LMAN_SYM_OUTLINE 0,0,100,-50
J 2
(-10150 5800);
DISPLAY 0.468085 (-10150 5800);
PAINT GREEN (-10150 5800);
DISPLAY INVISIBLE (-10150 5800);
FORCEPROP 2 LAST CDS_LIB cls
J 0
(-10150 5800);
DISPLAY INVISIBLE (-10150 5800);
FORCEPROP 1 LAST BODY_TYPE PLUMBING
J 2
(-10165 5785);
DISPLAY 0.808511 (-10165 5785);
PAINT GREEN (-10165 5785);
DISPLAY INVISIBLE (-10165 5785);
FORCEPROP 1 LAST PATH I150
J 2
(-10185 5800);
DISPLAY 0.808511 (-10185 5800);
PAINT GREEN (-10185 5800);
DISPLAY INVISIBLE (-10185 5800);
FORCEADD CAPACITOR..2
R 2
(-10650 6350);
FORCEPROP 1 LAST $LOCATION C246
J 2
(-10700 6200);
DISPLAY 1.212766 (-10700 6200);
PAINT GREEN (-10700 6200);
FORCEPROP 0 LAST CDS_LOCATION C246
J 0
(-10700 6500);
DISPLAY 1.021277 (-10700 6500);
DISPLAY INVISIBLE (-10700 6500);
FORCEPROP 0 LAST $SEC 1
J 0
(-10700 6500);
DISPLAY 0.680851 (-10700 6500);
PAINT MONO (-10700 6500);
DISPLAY INVISIBLE (-10700 6500);
FORCEPROP 0 LAST CDS_SEC 1
J 0
(-10700 6500);
DISPLAY 1.021277 (-10700 6500);
DISPLAY INVISIBLE (-10700 6500);
FORCEPROP 0 LASTPIN (-10650 6450) $PN 1
R 1
J 0
(-10660 6460);
DISPLAY 0.680851 (-10660 6460);
PAINT MONO (-10660 6460);
FORCEPROP 0 LASTPIN (-10650 6200) $PN 2
R 1
J 2
(-10660 6190);
DISPLAY 0.680851 (-10660 6190);
PAINT MONO (-10660 6190);
FORCEPROP 0 LAST PACKAGE 0402
J 0
(-10950 6300);
DISPLAY 1.021277 (-10950 6300);
FORCEPROP 0 LAST VOLTAGE 6.3V
J 0
(-10950 6100);
DISPLAY 1.021277 (-10950 6100);
FORCEPROP 1 LAST VALUE 10UF
J 2
(-10700 6400);
DISPLAY 1.212766 (-10700 6400);
PAINT GREEN (-10700 6400);
FORCEPROP 2 LAST CDS_LIB passive
J 0
(-10650 6350);
DISPLAY INVISIBLE (-10650 6350);
FORCEPROP 1 LAST CDS_LMAN_SYM_OUTLINE -50,0,50,-50
J 2
(-10650 6350);
DISPLAY 0.468085 (-10650 6350);
PAINT GREEN (-10650 6350);
DISPLAY INVISIBLE (-10650 6350);
FORCEPROP 1 LAST CLS_PN G105-0C106-BM
J 2
(-10550 6400);
DISPLAY 1.212766 (-10550 6400);
PAINT GREEN (-10550 6400);
DISPLAY INVISIBLE (-10550 6400);
FORCEPROP 1 LAST TOLERANCE 20%
J 2
(-10500 6450);
DISPLAY 1.212766 (-10500 6450);
PAINT GREEN (-10500 6450);
DISPLAY INVISIBLE (-10500 6450);
FORCEPROP 1 LAST PATH I151
J 2
(-10550 6400);
DISPLAY 1.212766 (-10550 6400);
PAINT GREEN (-10550 6400);
DISPLAY INVISIBLE (-10550 6400);
FORCEADD CAPACITOR..2
R 2
(-11650 6350);
FORCEPROP 1 LAST $LOCATION C244
J 2
(-11800 6200);
DISPLAY 1.212766 (-11800 6200);
PAINT GREEN (-11800 6200);
FORCEPROP 0 LAST CDS_LOCATION C244
J 0
(-11700 6500);
DISPLAY 1.021277 (-11700 6500);
DISPLAY INVISIBLE (-11700 6500);
FORCEPROP 0 LAST $SEC 1
J 0
(-11700 6500);
DISPLAY 0.680851 (-11700 6500);
PAINT MONO (-11700 6500);
DISPLAY INVISIBLE (-11700 6500);
FORCEPROP 0 LAST CDS_SEC 1
J 0
(-11700 6500);
DISPLAY 1.021277 (-11700 6500);
DISPLAY INVISIBLE (-11700 6500);
FORCEPROP 0 LASTPIN (-11650 6450) $PN 1
R 1
J 0
(-11660 6460);
DISPLAY 0.680851 (-11660 6460);
PAINT MONO (-11660 6460);
FORCEPROP 0 LASTPIN (-11650 6200) $PN 2
R 1
J 2
(-11660 6190);
DISPLAY 0.680851 (-11660 6190);
PAINT MONO (-11660 6190);
FORCEPROP 1 LAST VALUE 0.1UF
J 2
(-11700 6400);
DISPLAY 1.212766 (-11700 6400);
PAINT GREEN (-11700 6400);
FORCEPROP 0 LAST VOLTAGE 25V
J 0
(-12000 6100);
DISPLAY 1.021277 (-12000 6100);
FORCEPROP 0 LAST PACKAGE 0402
J 0
(-12000 6300);
DISPLAY 1.021277 (-12000 6300);
FORCEPROP 2 LAST CDS_LIB passive
J 0
(-11650 6350);
DISPLAY INVISIBLE (-11650 6350);
FORCEPROP 1 LAST CDS_LMAN_SYM_OUTLINE -50,0,50,-50
J 2
(-11650 6350);
DISPLAY 0.468085 (-11650 6350);
PAINT GREEN (-11650 6350);
DISPLAY INVISIBLE (-11650 6350);
FORCEPROP 1 LAST CLS_PN G105-0B104-EK
J 2
(-11550 6400);
DISPLAY 1.212766 (-11550 6400);
PAINT GREEN (-11550 6400);
DISPLAY INVISIBLE (-11550 6400);
FORCEPROP 1 LAST TOLERANCE 10%
J 2
(-11500 6450);
DISPLAY 1.212766 (-11500 6450);
PAINT GREEN (-11500 6450);
DISPLAY INVISIBLE (-11500 6450);
FORCEPROP 1 LAST PATH I152
J 2
(-11550 6400);
DISPLAY 1.212766 (-11550 6400);
PAINT GREEN (-11550 6400);
DISPLAY INVISIBLE (-11550 6400);
FORCEADD CAPACITOR..2
R 2
(-11650 2800);
FORCEPROP 1 LAST $LOCATION C245
J 2
(-11700 2650);
DISPLAY 1.212766 (-11700 2650);
PAINT GREEN (-11700 2650);
FORCEPROP 0 LAST CDS_LOCATION C245
J 0
(-11700 2950);
DISPLAY 1.021277 (-11700 2950);
DISPLAY INVISIBLE (-11700 2950);
FORCEPROP 0 LAST $SEC 1
J 0
(-11700 2950);
DISPLAY 0.680851 (-11700 2950);
PAINT MONO (-11700 2950);
DISPLAY INVISIBLE (-11700 2950);
FORCEPROP 0 LAST CDS_SEC 1
J 0
(-11700 2950);
DISPLAY 1.021277 (-11700 2950);
DISPLAY INVISIBLE (-11700 2950);
FORCEPROP 0 LASTPIN (-11650 2900) $PN 1
R 1
J 0
(-11660 2910);
DISPLAY 0.680851 (-11660 2910);
PAINT MONO (-11660 2910);
FORCEPROP 0 LASTPIN (-11650 2650) $PN 2
R 1
J 2
(-11660 2640);
DISPLAY 0.680851 (-11660 2640);
PAINT MONO (-11660 2640);
FORCEPROP 1 LAST VALUE 0.1UF
J 2
(-11700 2850);
DISPLAY 1.212766 (-11700 2850);
PAINT GREEN (-11700 2850);
FORCEPROP 0 LAST PACKAGE 0402
J 0
(-11900 2750);
DISPLAY 1.021277 (-11900 2750);
FORCEPROP 0 LAST VOLTAGE 25V
J 0
(-11900 2550);
DISPLAY 1.021277 (-11900 2550);
FORCEPROP 1 LAST CLS_PN G105-0B104-EK
J 2
(-11550 2850);
DISPLAY 1.212766 (-11550 2850);
PAINT GREEN (-11550 2850);
DISPLAY INVISIBLE (-11550 2850);
FORCEPROP 1 LAST CDS_LMAN_SYM_OUTLINE -50,0,50,-50
J 2
(-11650 2800);
DISPLAY 0.468085 (-11650 2800);
PAINT GREEN (-11650 2800);
DISPLAY INVISIBLE (-11650 2800);
FORCEPROP 2 LAST CDS_LIB passive
J 0
(-11650 2800);
DISPLAY INVISIBLE (-11650 2800);
FORCEPROP 1 LAST TOLERANCE 10%
J 2
(-11500 2900);
DISPLAY 1.212766 (-11500 2900);
PAINT GREEN (-11500 2900);
DISPLAY INVISIBLE (-11500 2900);
FORCEPROP 1 LAST PATH I153
J 2
(-11550 2850);
DISPLAY 1.212766 (-11550 2850);
PAINT GREEN (-11550 2850);
DISPLAY INVISIBLE (-11550 2850);
FORCEADD CAPACITOR..2
R 2
(-10650 2800);
FORCEPROP 1 LAST $LOCATION C247
J 2
(-10700 2650);
DISPLAY 1.212766 (-10700 2650);
PAINT GREEN (-10700 2650);
FORCEPROP 0 LAST CDS_LOCATION C247
J 0
(-10700 2950);
DISPLAY 1.021277 (-10700 2950);
DISPLAY INVISIBLE (-10700 2950);
FORCEPROP 0 LAST $SEC 1
J 0
(-10700 2950);
DISPLAY 0.680851 (-10700 2950);
PAINT MONO (-10700 2950);
DISPLAY INVISIBLE (-10700 2950);
FORCEPROP 0 LAST CDS_SEC 1
J 0
(-10700 2950);
DISPLAY 1.021277 (-10700 2950);
DISPLAY INVISIBLE (-10700 2950);
FORCEPROP 0 LASTPIN (-10650 2900) $PN 1
R 1
J 0
(-10660 2910);
DISPLAY 0.680851 (-10660 2910);
PAINT MONO (-10660 2910);
FORCEPROP 0 LASTPIN (-10650 2650) $PN 2
R 1
J 2
(-10660 2640);
DISPLAY 0.680851 (-10660 2640);
PAINT MONO (-10660 2640);
FORCEPROP 0 LAST VOLTAGE 6.3V
J 0
(-10900 2550);
DISPLAY 1.021277 (-10900 2550);
FORCEPROP 1 LAST VALUE 10UF
J 2
(-10700 2850);
DISPLAY 1.212766 (-10700 2850);
PAINT GREEN (-10700 2850);
FORCEPROP 0 LAST PACKAGE 0402
J 0
(-10950 2750);
DISPLAY 1.021277 (-10950 2750);
FORCEPROP 1 LAST TOLERANCE 20%
J 2
(-10500 2900);
DISPLAY 1.212766 (-10500 2900);
PAINT GREEN (-10500 2900);
DISPLAY INVISIBLE (-10500 2900);
FORCEPROP 2 LAST CDS_LIB passive
J 0
(-10650 2800);
DISPLAY INVISIBLE (-10650 2800);
FORCEPROP 1 LAST CDS_LMAN_SYM_OUTLINE -50,0,50,-50
J 2
(-10650 2800);
DISPLAY 0.468085 (-10650 2800);
PAINT GREEN (-10650 2800);
DISPLAY INVISIBLE (-10650 2800);
FORCEPROP 1 LAST CLS_PN G105-0C106-BM
J 2
(-10550 2850);
DISPLAY 1.212766 (-10550 2850);
PAINT GREEN (-10550 2850);
DISPLAY INVISIBLE (-10550 2850);
FORCEPROP 1 LAST PATH I154
J 2
(-10550 2850);
DISPLAY 1.212766 (-10550 2850);
PAINT GREEN (-10550 2850);
DISPLAY INVISIBLE (-10550 2850);
FORCEADD GND_SG..1
R 2
(-10150 2250);
FORCEPROP 3 LASTPIN (-10200 2300) SIG_NAME SG\g
J 0
(-10190 2310);
DISPLAY 0.659574 (-10190 2310);
PAINT MONO (-10190 2310);
DISPLAY INVISIBLE (-10190 2310);
FORCEPROP 1 LAST HDL_POWER SG
J 1
(-10205 2155);
DISPLAY 0.808511 (-10205 2155);
PAINT GREEN (-10205 2155);
FORCEPROP 1 LAST CDS_LMAN_SYM_OUTLINE 0,0,100,-50
J 2
(-10150 2250);
DISPLAY 0.468085 (-10150 2250);
PAINT GREEN (-10150 2250);
DISPLAY INVISIBLE (-10150 2250);
FORCEPROP 2 LAST CDS_LIB cls
J 0
(-10150 2250);
DISPLAY INVISIBLE (-10150 2250);
FORCEPROP 1 LAST BODY_TYPE PLUMBING
J 2
(-10165 2235);
DISPLAY 0.808511 (-10165 2235);
PAINT GREEN (-10165 2235);
DISPLAY INVISIBLE (-10165 2235);
FORCEPROP 1 LAST PATH I155
J 2
(-10185 2250);
DISPLAY 0.808511 (-10185 2250);
PAINT GREEN (-10185 2250);
DISPLAY INVISIBLE (-10185 2250);
FORCEADD RESISTOR..1
(-9350 2900);
FORCEPROP 1 LAST $LOCATION R236
J 2
(-9350 2950);
DISPLAY 1.212766 (-9350 2950);
PAINT GREEN (-9350 2950);
FORCEPROP 0 LAST CDS_LOCATION R236
J 0
(-9450 3050);
DISPLAY 1.021277 (-9450 3050);
DISPLAY INVISIBLE (-9450 3050);
FORCEPROP 0 LAST $SEC 1
J 0
(-9450 3050);
DISPLAY 0.680851 (-9450 3050);
PAINT MONO (-9450 3050);
DISPLAY INVISIBLE (-9450 3050);
FORCEPROP 0 LAST CDS_SEC 1
J 0
(-9450 3050);
DISPLAY 1.021277 (-9450 3050);
DISPLAY INVISIBLE (-9450 3050);
FORCEPROP 0 LASTPIN (-9450 2900) $PN 1
J 2
(-9460 2910);
DISPLAY 0.680851 (-9460 2910);
PAINT MONO (-9460 2910);
FORCEPROP 0 LASTPIN (-9200 2900) $PN 2
J 0
(-9190 2910);
DISPLAY 0.680851 (-9190 2910);
PAINT MONO (-9190 2910);
FORCEPROP 0 LAST PACKAGE 0402
J 0
(-9300 2950);
DISPLAY 1.021277 (-9300 2950);
FORCEPROP 1 LAST VALUE 4.7KOHM
J 0
(-9500 2800);
DISPLAY 1.212766 (-9500 2800);
PAINT GREEN (-9500 2800);
FORCEPROP 1 LAST CLS_PN G155-14701-01
J 0
(-9486 3100);
DISPLAY 1.212766 (-9486 3100);
PAINT GREEN (-9486 3100);
DISPLAY INVISIBLE (-9486 3100);
FORCEPROP 1 LAST CDS_LMAN_SYM_OUTLINE -50,50,100,-50
J 0
(-9350 2900);
DISPLAY 0.468085 (-9350 2900);
PAINT GREEN (-9350 2900);
DISPLAY INVISIBLE (-9350 2900);
FORCEPROP 2 LAST CDS_LIB passive
J 0
(-9350 2900);
DISPLAY INVISIBLE (-9350 2900);
FORCEPROP 1 LAST TOLERANCE 1%
J 0
(-9547 3155);
DISPLAY 1.212766 (-9547 3155);
PAINT GREEN (-9547 3155);
DISPLAY INVISIBLE (-9547 3155);
FORCEPROP 1 LAST PATH I156
J 0
(-9547 3005);
DISPLAY 1.212766 (-9547 3005);
PAINT GREEN (-9547 3005);
DISPLAY INVISIBLE (-9547 3005);
FORCEADD CAPACITOR..2
R 2
(-10200 2820);
FORCEPROP 1 LAST $LOCATION C249
J 2
(-10250 2670);
DISPLAY 1.212766 (-10250 2670);
PAINT GREEN (-10250 2670);
FORCEPROP 0 LAST CDS_LOCATION C249
J 0
(-10250 2950);
DISPLAY 1.021277 (-10250 2950);
DISPLAY INVISIBLE (-10250 2950);
FORCEPROP 0 LAST $SEC 1
J 0
(-10250 2950);
DISPLAY 0.680851 (-10250 2950);
PAINT MONO (-10250 2950);
DISPLAY INVISIBLE (-10250 2950);
FORCEPROP 0 LAST CDS_SEC 1
J 0
(-10250 2950);
DISPLAY 1.021277 (-10250 2950);
DISPLAY INVISIBLE (-10250 2950);
FORCEPROP 0 LASTPIN (-10200 2920) $PN 1
R 1
J 0
(-10210 2930);
DISPLAY 0.680851 (-10210 2930);
PAINT MONO (-10210 2930);
FORCEPROP 0 LASTPIN (-10200 2670) $PN 2
R 1
J 2
(-10210 2660);
DISPLAY 0.680851 (-10210 2660);
PAINT MONO (-10210 2660);
FORCEPROP 1 LAST VALUE 0.1UF
J 2
(-10250 2870);
DISPLAY 1.212766 (-10250 2870);
PAINT GREEN (-10250 2870);
FORCEPROP 0 LAST PACKAGE 0402
J 0
(-10450 2750);
DISPLAY 1.021277 (-10450 2750);
FORCEPROP 0 LAST VOLTAGE 25V
J 0
(-10450 2600);
DISPLAY 1.021277 (-10450 2600);
FORCEPROP 1 LAST CLS_PN G105-0B104-EK
J 2
(-10100 2870);
DISPLAY 1.212766 (-10100 2870);
PAINT GREEN (-10100 2870);
DISPLAY INVISIBLE (-10100 2870);
FORCEPROP 1 LAST CDS_LMAN_SYM_OUTLINE -50,0,50,-50
J 2
(-10200 2820);
DISPLAY 0.468085 (-10200 2820);
PAINT GREEN (-10200 2820);
DISPLAY INVISIBLE (-10200 2820);
FORCEPROP 2 LAST CDS_LIB passive
J 0
(-10200 2820);
DISPLAY INVISIBLE (-10200 2820);
FORCEPROP 1 LAST TOLERANCE 10%
J 2
(-10050 2920);
DISPLAY 1.212766 (-10050 2920);
PAINT GREEN (-10050 2920);
DISPLAY INVISIBLE (-10050 2920);
FORCEPROP 1 LAST PATH I158
J 2
(-10100 2870);
DISPLAY 1.212766 (-10100 2870);
PAINT GREEN (-10100 2870);
DISPLAY INVISIBLE (-10100 2870);
FORCEADD FERRITEBEAD..1
R 2
(-11050 3150);
FORCEPROP 1 LAST $LOCATION L10
J 0
(-11550 3150);
DISPLAY 1.212766 (-11550 3150);
PAINT GREEN (-11550 3150);
FORCEPROP 0 LAST CDS_LOCATION L10
J 0
(-10850 3300);
DISPLAY 1.021277 (-10850 3300);
DISPLAY INVISIBLE (-10850 3300);
FORCEPROP 0 LAST $SEC 1
J 0
(-10850 3300);
DISPLAY 0.680851 (-10850 3300);
PAINT MONO (-10850 3300);
DISPLAY INVISIBLE (-10850 3300);
FORCEPROP 0 LAST CDS_SEC 1
J 0
(-10850 3300);
DISPLAY 1.021277 (-10850 3300);
DISPLAY INVISIBLE (-10850 3300);
FORCEPROP 0 LASTPIN (-10950 3100) $PN 1
J 0
(-10940 3110);
DISPLAY 0.680851 (-10940 3110);
PAINT MONO (-10940 3110);
FORCEPROP 0 LASTPIN (-11350 3100) $PN 2
J 2
(-11360 3110);
DISPLAY 0.680851 (-11360 3110);
PAINT MONO (-11360 3110);
FORCEPROP 2 LAST DCR 1300MA 0.15OHM
J 2
(-10800 3000);
FORCEPROP 1 LAST VALUE 600OHM
J 2
(-10550 3200);
DISPLAY 1.212766 (-10550 3200);
PAINT GREEN (-10550 3200);
FORCEPROP 0 LAST PACKAGE 0603
J 0
(-11250 3200);
DISPLAY 1.021277 (-11250 3200);
FORCEPROP 1 LAST CLS_PN G191-10097-01
J 0
(-11000 3200);
DISPLAY 1.212766 (-11000 3200);
PAINT GREEN (-11000 3200);
DISPLAY INVISIBLE (-11000 3200);
FORCEPROP 2 LAST CDS_LIB passive
J 0
(-11050 3150);
DISPLAY INVISIBLE (-11050 3150);
FORCEPROP 1 LAST CDS_LMAN_SYM_OUTLINE 0,0,200,-100
J 2
(-11050 3150);
DISPLAY 0.468085 (-11050 3150);
PAINT GREEN (-11050 3150);
DISPLAY INVISIBLE (-11050 3150);
FORCEPROP 1 LAST PATH I159
J 0
(-11000 3200);
DISPLAY 1.212766 (-11000 3200);
PAINT GREEN (-11000 3200);
DISPLAY INVISIBLE (-11000 3200);
FORCEPROP 1 LAST TOLERANCE 25%
J 2
(-10950 3200);
DISPLAY 1.212766 (-10950 3200);
PAINT GREEN (-10950 3200);
DISPLAY INVISIBLE (-10950 3200);
FORCEADD CAPACITOR..1
(-6150 6550);
FORCEPROP 1 LAST $LOCATION C252
J 2
(-6300 6550);
DISPLAY 1.212766 (-6300 6550);
PAINT GREEN (-6300 6550);
FORCEPROP 0 LAST CDS_LOCATION C252
J 0
(-5900 6650);
DISPLAY 1.021277 (-5900 6650);
DISPLAY INVISIBLE (-5900 6650);
FORCEPROP 0 LAST $SEC 1
J 0
(-5900 6650);
DISPLAY 0.680851 (-5900 6650);
PAINT MONO (-5900 6650);
DISPLAY INVISIBLE (-5900 6650);
FORCEPROP 0 LAST CDS_SEC 1
J 0
(-5900 6650);
DISPLAY 1.021277 (-5900 6650);
DISPLAY INVISIBLE (-5900 6650);
FORCEPROP 0 LASTPIN (-6250 6550) $PN 1
J 2
(-6260 6560);
DISPLAY 0.680851 (-6260 6560);
PAINT MONO (-6260 6560);
FORCEPROP 0 LASTPIN (-6000 6550) $PN 2
J 0
(-5990 6560);
DISPLAY 0.680851 (-5990 6560);
PAINT MONO (-5990 6560);
FORCEPROP 0 LAST PACKAGE 0402
J 0
(-6200 6400);
DISPLAY 1.021277 (-6200 6400);
FORCEPROP 0 LAST VOLTAGE 10V
J 0
(-5950 6400);
DISPLAY 1.021277 (-5950 6400);
FORCEPROP 1 LAST VALUE 0.1UF
J 0
(-5900 6550);
DISPLAY 1.212766 (-5900 6550);
PAINT GREEN (-5900 6550);
FORCEPROP 1 LAST TOLERANCE 10%
J 2
(-6250 6650);
DISPLAY 1.212766 (-6250 6650);
PAINT GREEN (-6250 6650);
DISPLAY INVISIBLE (-6250 6650);
FORCEPROP 2 LAST CDS_LIB passive
J 0
(-6150 6550);
DISPLAY INVISIBLE (-6150 6550);
FORCEPROP 1 LAST CDS_LMAN_SYM_OUTLINE 0,50,50,-50
J 0
(-6150 6550);
DISPLAY 0.468085 (-6150 6550);
PAINT GREEN (-6150 6550);
DISPLAY INVISIBLE (-6150 6550);
FORCEPROP 1 LAST CLS_PN G105-0B104-CK
J 2
(-6200 6650);
DISPLAY 1.212766 (-6200 6650);
PAINT GREEN (-6200 6650);
DISPLAY INVISIBLE (-6200 6650);
FORCEPROP 1 LAST PATH I160
J 2
(-6200 6650);
DISPLAY 1.212766 (-6200 6650);
PAINT GREEN (-6200 6650);
DISPLAY INVISIBLE (-6200 6650);
FORCEADD CAPACITOR..1
(-6150 6650);
FORCEPROP 1 LAST $LOCATION C251
J 2
(-6300 6650);
DISPLAY 1.212766 (-6300 6650);
PAINT GREEN (-6300 6650);
FORCEPROP 0 LAST CDS_LOCATION C251
J 0
(-5900 6750);
DISPLAY 1.021277 (-5900 6750);
DISPLAY INVISIBLE (-5900 6750);
FORCEPROP 0 LAST $SEC 1
J 0
(-5900 6750);
DISPLAY 0.680851 (-5900 6750);
PAINT MONO (-5900 6750);
DISPLAY INVISIBLE (-5900 6750);
FORCEPROP 0 LAST CDS_SEC 1
J 0
(-5900 6750);
DISPLAY 1.021277 (-5900 6750);
DISPLAY INVISIBLE (-5900 6750);
FORCEPROP 0 LASTPIN (-6250 6650) $PN 1
J 2
(-6260 6660);
DISPLAY 0.680851 (-6260 6660);
PAINT MONO (-6260 6660);
FORCEPROP 0 LASTPIN (-6000 6650) $PN 2
J 0
(-5990 6660);
DISPLAY 0.680851 (-5990 6660);
PAINT MONO (-5990 6660);
FORCEPROP 0 LAST PACKAGE 0402
J 0
(-6200 6750);
DISPLAY 1.021277 (-6200 6750);
FORCEPROP 1 LAST VALUE 0.1UF
J 0
(-5900 6650);
DISPLAY 1.212766 (-5900 6650);
PAINT GREEN (-5900 6650);
FORCEPROP 0 LAST VOLTAGE 10V
J 0
(-5950 6750);
DISPLAY 1.021277 (-5950 6750);
FORCEPROP 1 LAST TOLERANCE 10%
J 2
(-6250 6750);
DISPLAY 1.212766 (-6250 6750);
PAINT GREEN (-6250 6750);
DISPLAY INVISIBLE (-6250 6750);
FORCEPROP 2 LAST CDS_LIB passive
J 0
(-6150 6650);
DISPLAY INVISIBLE (-6150 6650);
FORCEPROP 1 LAST CDS_LMAN_SYM_OUTLINE 0,50,50,-50
J 0
(-6150 6650);
DISPLAY 0.468085 (-6150 6650);
PAINT GREEN (-6150 6650);
DISPLAY INVISIBLE (-6150 6650);
FORCEPROP 1 LAST CLS_PN G105-0B104-CK
J 2
(-6200 6750);
DISPLAY 1.212766 (-6200 6750);
PAINT GREEN (-6200 6750);
DISPLAY INVISIBLE (-6200 6750);
FORCEPROP 1 LAST PATH I161
J 2
(-6200 6750);
DISPLAY 1.212766 (-6200 6750);
PAINT GREEN (-6200 6750);
DISPLAY INVISIBLE (-6200 6750);
FORCEADD GND_SG..1
(-8000 2400);
FORCEPROP 3 LASTPIN (-7950 2450) SIG_NAME SG\g
J 0
(-7940 2460);
DISPLAY 0.659574 (-7940 2460);
PAINT MONO (-7940 2460);
DISPLAY INVISIBLE (-7940 2460);
FORCEPROP 1 LAST HDL_POWER SG
J 1
(-7950 2300);
DISPLAY 0.808511 (-7950 2300);
PAINT GREEN (-7950 2300);
FORCEPROP 1 LAST CDS_LMAN_SYM_OUTLINE 0,0,100,-50
J 0
(-8000 2400);
DISPLAY 0.468085 (-8000 2400);
PAINT GREEN (-8000 2400);
DISPLAY INVISIBLE (-8000 2400);
FORCEPROP 2 LAST CDS_LIB cls
J 0
(-8000 2400);
DISPLAY INVISIBLE (-8000 2400);
FORCEPROP 1 LAST BODY_TYPE PLUMBING
J 0
(-7985 2385);
DISPLAY 0.808511 (-7985 2385);
PAINT GREEN (-7985 2385);
DISPLAY INVISIBLE (-7985 2385);
FORCEPROP 1 LAST PATH I167
J 0
(-7965 2400);
DISPLAY 0.808511 (-7965 2400);
PAINT GREEN (-7965 2400);
DISPLAY INVISIBLE (-7965 2400);
FORCEADD GND_SG..1
(-8000 5950);
FORCEPROP 3 LASTPIN (-7950 6000) SIG_NAME SG\g
J 0
(-7940 6010);
DISPLAY 0.659574 (-7940 6010);
PAINT MONO (-7940 6010);
DISPLAY INVISIBLE (-7940 6010);
FORCEPROP 1 LAST HDL_POWER SG
J 1
(-7950 5850);
DISPLAY 0.808511 (-7950 5850);
PAINT GREEN (-7950 5850);
FORCEPROP 2 LAST CDS_LIB cls
J 0
(-8000 5950);
DISPLAY INVISIBLE (-8000 5950);
FORCEPROP 1 LAST CDS_LMAN_SYM_OUTLINE 0,0,100,-50
J 0
(-8000 5950);
DISPLAY 0.468085 (-8000 5950);
PAINT GREEN (-8000 5950);
DISPLAY INVISIBLE (-8000 5950);
FORCEPROP 1 LAST BODY_TYPE PLUMBING
J 0
(-7985 5935);
DISPLAY 0.808511 (-7985 5935);
PAINT GREEN (-7985 5935);
DISPLAY INVISIBLE (-7985 5935);
FORCEPROP 1 LAST PATH I168
J 0
(-7965 5950);
DISPLAY 0.808511 (-7965 5950);
PAINT GREEN (-7965 5950);
DISPLAY INVISIBLE (-7965 5950);
FORCEADD RESISTOR..1
R 5
(-7000 6150);
FORCEPROP 1 LAST $LOCATION R239
J 2
(-6800 6000);
DISPLAY 1.212766 (-6800 6000);
PAINT GREEN (-6800 6000);
FORCEPROP 0 LAST CDS_LOCATION R239
J 0
(-6950 6200);
DISPLAY 1.021277 (-6950 6200);
DISPLAY INVISIBLE (-6950 6200);
FORCEPROP 0 LAST $SEC 1
J 0
(-6950 6200);
DISPLAY 0.680851 (-6950 6200);
PAINT MONO (-6950 6200);
DISPLAY INVISIBLE (-6950 6200);
FORCEPROP 0 LAST CDS_SEC 1
J 0
(-6950 6200);
DISPLAY 1.021277 (-6950 6200);
DISPLAY INVISIBLE (-6950 6200);
FORCEPROP 0 LASTPIN (-7000 6250) $PN 1
R 1
J 0
(-7010 6260);
DISPLAY 0.680851 (-7010 6260);
PAINT MONO (-7010 6260);
FORCEPROP 0 LASTPIN (-7000 6000) $PN 2
R 1
J 2
(-7010 5990);
DISPLAY 0.680851 (-7010 5990);
PAINT MONO (-7010 5990);
FORCEPROP 1 LAST VALUE 150OHM
J 0
(-6950 6150);
DISPLAY 0.978723 (-6950 6150);
PAINT GREEN (-6950 6150);
FORCEPROP 0 LAST PACKAGE 0402
J 0
(-6950 6250);
DISPLAY 1.021277 (-6950 6250);
FORCEPROP 0 LAST NO_ASSY TRUE
J 0
(-7250 6100);
DISPLAY 1.021277 (-7250 6100);
DISPLAY BOTH (-7250 6100);
FORCEPROP 1 LAST CLS_PN G155-11500-01
R 3
J 0
(-6800 6286);
DISPLAY 1.212766 (-6800 6286);
PAINT GREEN (-6800 6286);
DISPLAY INVISIBLE (-6800 6286);
FORCEPROP 2 LAST CDS_LIB passive
J 0
(-7000 6150);
DISPLAY INVISIBLE (-7000 6150);
FORCEPROP 1 LAST CDS_LMAN_SYM_OUTLINE -50,50,100,-50
R 3
J 0
(-7000 6150);
DISPLAY 0.468085 (-7000 6150);
PAINT GREEN (-7000 6150);
DISPLAY INVISIBLE (-7000 6150);
FORCEPROP 1 LAST TOLERANCE 1%
R 3
J 0
(-6745 6347);
DISPLAY 1.212766 (-6745 6347);
PAINT GREEN (-6745 6347);
DISPLAY INVISIBLE (-6745 6347);
FORCEPROP 1 LAST PATH I169
R 3
J 0
(-6895 6347);
DISPLAY 1.212766 (-6895 6347);
PAINT GREEN (-6895 6347);
DISPLAY INVISIBLE (-6895 6347);
FORCEADD RESISTOR..1
R 5
(-6650 6150);
FORCEPROP 1 LAST $LOCATION R241
J 2
(-6450 6000);
DISPLAY 1.212766 (-6450 6000);
PAINT GREEN (-6450 6000);
FORCEPROP 0 LAST CDS_LOCATION R241
J 0
(-6600 6200);
DISPLAY 1.021277 (-6600 6200);
DISPLAY INVISIBLE (-6600 6200);
FORCEPROP 0 LAST $SEC 1
J 0
(-6600 6200);
DISPLAY 0.680851 (-6600 6200);
PAINT MONO (-6600 6200);
DISPLAY INVISIBLE (-6600 6200);
FORCEPROP 0 LAST CDS_SEC 1
J 0
(-6600 6200);
DISPLAY 1.021277 (-6600 6200);
DISPLAY INVISIBLE (-6600 6200);
FORCEPROP 0 LASTPIN (-6650 6250) $PN 1
R 1
J 0
(-6660 6260);
DISPLAY 0.680851 (-6660 6260);
PAINT MONO (-6660 6260);
FORCEPROP 0 LASTPIN (-6650 6000) $PN 2
R 1
J 2
(-6660 5990);
DISPLAY 0.680851 (-6660 5990);
PAINT MONO (-6660 5990);
FORCEPROP 0 LAST PACKAGE 0402
J 0
(-6600 6250);
DISPLAY 1.021277 (-6600 6250);
FORCEPROP 1 LAST VALUE 150OHM
J 0
(-6600 6150);
DISPLAY 0.978723 (-6600 6150);
PAINT GREEN (-6600 6150);
FORCEPROP 0 LAST NO_ASSY TRUE
J 0
(-6650 6100);
DISPLAY 1.021277 (-6650 6100);
DISPLAY BOTH (-6650 6100);
FORCEPROP 1 LAST CLS_PN G155-11500-01
R 3
J 0
(-6450 6286);
DISPLAY 1.212766 (-6450 6286);
PAINT GREEN (-6450 6286);
DISPLAY INVISIBLE (-6450 6286);
FORCEPROP 2 LAST CDS_LIB passive
J 0
(-6650 6150);
DISPLAY INVISIBLE (-6650 6150);
FORCEPROP 1 LAST CDS_LMAN_SYM_OUTLINE -50,50,100,-50
R 3
J 0
(-6650 6150);
DISPLAY 0.468085 (-6650 6150);
PAINT GREEN (-6650 6150);
DISPLAY INVISIBLE (-6650 6150);
FORCEPROP 1 LAST TOLERANCE 1%
R 3
J 0
(-6395 6347);
DISPLAY 1.212766 (-6395 6347);
PAINT GREEN (-6395 6347);
DISPLAY INVISIBLE (-6395 6347);
FORCEPROP 1 LAST PATH I170
R 3
J 0
(-6545 6347);
DISPLAY 1.212766 (-6545 6347);
PAINT GREEN (-6545 6347);
DISPLAY INVISIBLE (-6545 6347);
FORCEADD GND_SG..1
(-7050 5700);
FORCEPROP 3 LASTPIN (-7000 5750) SIG_NAME SG\g
J 0
(-6990 5760);
DISPLAY 0.659574 (-6990 5760);
PAINT MONO (-6990 5760);
DISPLAY INVISIBLE (-6990 5760);
FORCEPROP 1 LAST HDL_POWER SG
J 1
(-7000 5600);
DISPLAY 0.808511 (-7000 5600);
PAINT GREEN (-7000 5600);
FORCEPROP 2 LAST CDS_LIB cls
J 0
(-7050 5700);
DISPLAY INVISIBLE (-7050 5700);
FORCEPROP 1 LAST CDS_LMAN_SYM_OUTLINE 0,0,100,-50
J 0
(-7050 5700);
DISPLAY 0.468085 (-7050 5700);
PAINT GREEN (-7050 5700);
DISPLAY INVISIBLE (-7050 5700);
FORCEPROP 1 LAST BODY_TYPE PLUMBING
J 0
(-7035 5685);
DISPLAY 0.808511 (-7035 5685);
PAINT GREEN (-7035 5685);
DISPLAY INVISIBLE (-7035 5685);
FORCEPROP 1 LAST PATH I171
J 0
(-7015 5700);
DISPLAY 0.808511 (-7015 5700);
PAINT GREEN (-7015 5700);
DISPLAY INVISIBLE (-7015 5700);
FORCEADD RESISTOR..1
R 5
(-7000 2600);
FORCEPROP 1 LAST $LOCATION R240
J 2
(-6800 2450);
DISPLAY 1.212766 (-6800 2450);
PAINT GREEN (-6800 2450);
FORCEPROP 0 LAST CDS_LOCATION R240
J 0
(-6950 2650);
DISPLAY 1.021277 (-6950 2650);
DISPLAY INVISIBLE (-6950 2650);
FORCEPROP 0 LAST $SEC 1
J 0
(-6950 2650);
DISPLAY 0.680851 (-6950 2650);
PAINT MONO (-6950 2650);
DISPLAY INVISIBLE (-6950 2650);
FORCEPROP 0 LAST CDS_SEC 1
J 0
(-6950 2650);
DISPLAY 1.021277 (-6950 2650);
DISPLAY INVISIBLE (-6950 2650);
FORCEPROP 0 LASTPIN (-7000 2700) $PN 1
R 1
J 0
(-7010 2710);
DISPLAY 0.680851 (-7010 2710);
PAINT MONO (-7010 2710);
FORCEPROP 0 LASTPIN (-7000 2450) $PN 2
R 1
J 2
(-7010 2440);
DISPLAY 0.680851 (-7010 2440);
PAINT MONO (-7010 2440);
FORCEPROP 0 LAST NO_ASSY TRUE
J 0
(-7250 2550);
DISPLAY 1.021277 (-7250 2550);
DISPLAY BOTH (-7250 2550);
FORCEPROP 0 LAST PACKAGE 0402
J 0
(-6950 2700);
DISPLAY 1.021277 (-6950 2700);
FORCEPROP 1 LAST VALUE 150OHM
J 0
(-6950 2600);
DISPLAY 0.978723 (-6950 2600);
PAINT GREEN (-6950 2600);
FORCEPROP 1 LAST CLS_PN G155-11500-01
R 3
J 0
(-6800 2736);
DISPLAY 1.212766 (-6800 2736);
PAINT GREEN (-6800 2736);
DISPLAY INVISIBLE (-6800 2736);
FORCEPROP 1 LAST CDS_LMAN_SYM_OUTLINE -50,50,100,-50
R 3
J 0
(-7000 2600);
DISPLAY 0.468085 (-7000 2600);
PAINT GREEN (-7000 2600);
DISPLAY INVISIBLE (-7000 2600);
FORCEPROP 2 LAST CDS_LIB passive
J 0
(-7000 2600);
DISPLAY INVISIBLE (-7000 2600);
FORCEPROP 1 LAST TOLERANCE 1%
R 3
J 0
(-6745 2797);
DISPLAY 1.212766 (-6745 2797);
PAINT GREEN (-6745 2797);
DISPLAY INVISIBLE (-6745 2797);
FORCEPROP 1 LAST PATH I172
R 3
J 0
(-6895 2797);
DISPLAY 1.212766 (-6895 2797);
PAINT GREEN (-6895 2797);
DISPLAY INVISIBLE (-6895 2797);
FORCEADD GND_SG..1
(-7050 2150);
FORCEPROP 3 LASTPIN (-7000 2200) SIG_NAME SG\g
J 0
(-6990 2210);
DISPLAY 0.659574 (-6990 2210);
PAINT MONO (-6990 2210);
DISPLAY INVISIBLE (-6990 2210);
FORCEPROP 1 LAST HDL_POWER SG
J 1
(-7000 2050);
DISPLAY 0.808511 (-7000 2050);
PAINT GREEN (-7000 2050);
FORCEPROP 1 LAST CDS_LMAN_SYM_OUTLINE 0,0,100,-50
J 0
(-7050 2150);
DISPLAY 0.468085 (-7050 2150);
PAINT GREEN (-7050 2150);
DISPLAY INVISIBLE (-7050 2150);
FORCEPROP 2 LAST CDS_LIB cls
J 0
(-7050 2150);
DISPLAY INVISIBLE (-7050 2150);
FORCEPROP 1 LAST BODY_TYPE PLUMBING
J 0
(-7035 2135);
DISPLAY 0.808511 (-7035 2135);
PAINT GREEN (-7035 2135);
DISPLAY INVISIBLE (-7035 2135);
FORCEPROP 1 LAST PATH I173
J 0
(-7015 2150);
DISPLAY 0.808511 (-7015 2150);
PAINT GREEN (-7015 2150);
DISPLAY INVISIBLE (-7015 2150);
FORCEADD RESISTOR..1
R 5
(-6650 2600);
FORCEPROP 1 LAST $LOCATION R242
J 2
(-6450 2450);
DISPLAY 1.212766 (-6450 2450);
PAINT GREEN (-6450 2450);
FORCEPROP 0 LAST CDS_LOCATION R242
J 0
(-6600 2650);
DISPLAY 1.021277 (-6600 2650);
DISPLAY INVISIBLE (-6600 2650);
FORCEPROP 0 LAST $SEC 1
J 0
(-6600 2650);
DISPLAY 0.680851 (-6600 2650);
PAINT MONO (-6600 2650);
DISPLAY INVISIBLE (-6600 2650);
FORCEPROP 0 LAST CDS_SEC 1
J 0
(-6600 2650);
DISPLAY 1.021277 (-6600 2650);
DISPLAY INVISIBLE (-6600 2650);
FORCEPROP 0 LASTPIN (-6650 2700) $PN 1
R 1
J 0
(-6660 2710);
DISPLAY 0.680851 (-6660 2710);
PAINT MONO (-6660 2710);
FORCEPROP 0 LASTPIN (-6650 2450) $PN 2
R 1
J 2
(-6660 2440);
DISPLAY 0.680851 (-6660 2440);
PAINT MONO (-6660 2440);
FORCEPROP 0 LAST NO_ASSY TRUE
J 0
(-6650 2550);
DISPLAY 1.021277 (-6650 2550);
DISPLAY BOTH (-6650 2550);
FORCEPROP 0 LAST PACKAGE 0402
J 0
(-6600 2700);
DISPLAY 1.021277 (-6600 2700);
FORCEPROP 1 LAST VALUE 150OHM
J 0
(-6600 2600);
DISPLAY 0.978723 (-6600 2600);
PAINT GREEN (-6600 2600);
FORCEPROP 1 LAST CLS_PN G155-11500-01
R 3
J 0
(-6450 2736);
DISPLAY 1.212766 (-6450 2736);
PAINT GREEN (-6450 2736);
DISPLAY INVISIBLE (-6450 2736);
FORCEPROP 1 LAST CDS_LMAN_SYM_OUTLINE -50,50,100,-50
R 3
J 0
(-6650 2600);
DISPLAY 0.468085 (-6650 2600);
PAINT GREEN (-6650 2600);
DISPLAY INVISIBLE (-6650 2600);
FORCEPROP 2 LAST CDS_LIB passive
J 0
(-6650 2600);
DISPLAY INVISIBLE (-6650 2600);
FORCEPROP 1 LAST TOLERANCE 1%
R 3
J 0
(-6395 2797);
DISPLAY 1.212766 (-6395 2797);
PAINT GREEN (-6395 2797);
DISPLAY INVISIBLE (-6395 2797);
FORCEPROP 1 LAST PATH I174
R 3
J 0
(-6545 2797);
DISPLAY 1.212766 (-6545 2797);
PAINT GREEN (-6545 2797);
DISPLAY INVISIBLE (-6545 2797);
FORCEADD VCC..1
(-11950 3300);
FORCEPROP 3 LASTPIN (-11900 3250) SIG_NAME XP3R3V\g
J 0
(-11890 3260);
DISPLAY 0.659574 (-11890 3260);
PAINT MONO (-11890 3260);
DISPLAY INVISIBLE (-11890 3260);
FORCEPROP 0 LAST VOLTAGE 3.3
J 0
(-12100 3450);
DISPLAY 1.021277 (-12100 3450);
DISPLAY BOTH (-12100 3450);
FORCEPROP 1 LAST HDL_POWER XP3R3V
J 1
(-11895 3355);
DISPLAY 1.021277 (-11895 3355);
PAINT GREEN (-11895 3355);
FORCEPROP 2 LAST CDS_LIB cls
J 0
(-11950 3300);
DISPLAY INVISIBLE (-11950 3300);
FORCEPROP 1 LAST CDS_LMAN_SYM_OUTLINE -250,250,250,-250
J 0
(-11950 3300);
DISPLAY 0.468085 (-11950 3300);
PAINT GREEN (-11950 3300);
DISPLAY INVISIBLE (-11950 3300);
FORCEPROP 1 LAST BODY_TYPE PLUMBING
J 0
(-11995 3257);
DISPLAY 0.340426 (-11995 3257);
PAINT GREEN (-11995 3257);
DISPLAY INVISIBLE (-11995 3257);
FORCEPROP 1 LAST PATH I176
J 0
(-11915 3390);
DISPLAY 0.808511 (-11915 3390);
PAINT GREEN (-11915 3390);
DISPLAY INVISIBLE (-11915 3390);
FORCEADD VCC..1
(-11950 6850);
FORCEPROP 3 LASTPIN (-11900 6800) SIG_NAME XP3R3V\g
J 0
(-11890 6810);
DISPLAY 0.659574 (-11890 6810);
PAINT MONO (-11890 6810);
DISPLAY INVISIBLE (-11890 6810);
FORCEPROP 0 LAST VOLTAGE 3.3
J 0
(-12100 7000);
DISPLAY 1.021277 (-12100 7000);
DISPLAY BOTH (-12100 7000);
FORCEPROP 1 LAST HDL_POWER XP3R3V
J 1
(-11895 6905);
DISPLAY 1.021277 (-11895 6905);
PAINT GREEN (-11895 6905);
FORCEPROP 1 LAST CDS_LMAN_SYM_OUTLINE -250,250,250,-250
J 0
(-11950 6850);
DISPLAY 0.468085 (-11950 6850);
PAINT GREEN (-11950 6850);
DISPLAY INVISIBLE (-11950 6850);
FORCEPROP 2 LAST CDS_LIB cls
J 0
(-11950 6850);
DISPLAY INVISIBLE (-11950 6850);
FORCEPROP 1 LAST BODY_TYPE PLUMBING
J 0
(-11995 6807);
DISPLAY 0.340426 (-11995 6807);
PAINT GREEN (-11995 6807);
DISPLAY INVISIBLE (-11995 6807);
FORCEPROP 1 LAST PATH I177
J 0
(-11915 6940);
DISPLAY 0.808511 (-11915 6940);
PAINT GREEN (-11915 6940);
DISPLAY INVISIBLE (-11915 6940);
FORCEADD OFFPAGE_IN..1
(-9700 6150);
FORCEPROP 2 LAST $XR0 25C9<> 
J 0
(-9914 6150);
DISPLAY 0.638298 (-9914 6150);
PAINT MONO (-9914 6150);
FORCEPROP 2 LASTPIN (-9650 6150) SIG_NAME CLK_200M_OE
J 0
(-9610 6160);
DISPLAY 1.021277 (-9610 6160);
FORCEPROP 1 LAST OFFPAGE TRUE
J 0
(-9690 6205);
DISPLAY 0.808511 (-9690 6205);
PAINT GREEN (-9690 6205);
DISPLAY INVISIBLE (-9690 6205);
FORCEPROP 1 LAST BODY_TYPE COMMENT
J 0
(-9690 6285);
DISPLAY 0.808511 (-9690 6285);
PAINT GREEN (-9690 6285);
DISPLAY INVISIBLE (-9690 6285);
FORCEPROP 1 LAST CDS_LMAN_SYM_OUTLINE -50,50,50,-50
J 0
(-9700 6150);
DISPLAY 0.468085 (-9700 6150);
PAINT GREEN (-9700 6150);
DISPLAY INVISIBLE (-9700 6150);
FORCEPROP 2 LAST CDS_LIB cls
J 0
(-9700 6150);
DISPLAY INVISIBLE (-9700 6150);
FORCEPROP 2 LAST PATH I178
J 0
(-9650 6250);
DISPLAY 1.021277 (-9650 6250);
DISPLAY INVISIBLE (-9650 6250);
FORCEADD OFFPAGE_IN..1
(-9700 2600);
FORCEPROP 2 LAST $XR0 25C9<> 
J 0
(-9914 2600);
DISPLAY 0.638298 (-9914 2600);
PAINT MONO (-9914 2600);
FORCEPROP 2 LASTPIN (-9650 2600) SIG_NAME CLK_125M_OE
J 0
(-9610 2610);
DISPLAY 1.021277 (-9610 2610);
FORCEPROP 2 LAST CDS_LIB cls
J 0
(-9700 2600);
DISPLAY INVISIBLE (-9700 2600);
FORCEPROP 1 LAST CDS_LMAN_SYM_OUTLINE -50,50,50,-50
J 0
(-9700 2600);
DISPLAY 0.468085 (-9700 2600);
PAINT GREEN (-9700 2600);
DISPLAY INVISIBLE (-9700 2600);
FORCEPROP 1 LAST BODY_TYPE COMMENT
J 0
(-9690 2735);
DISPLAY 0.808511 (-9690 2735);
PAINT GREEN (-9690 2735);
DISPLAY INVISIBLE (-9690 2735);
FORCEPROP 1 LAST OFFPAGE TRUE
J 0
(-9690 2655);
DISPLAY 0.808511 (-9690 2655);
PAINT GREEN (-9690 2655);
DISPLAY INVISIBLE (-9690 2655);
FORCEPROP 2 LAST PATH I179
J 0
(-9650 2700);
DISPLAY 1.021277 (-9650 2700);
DISPLAY INVISIBLE (-9650 2700);
FORCEADD SHEET_A1..1
(-100 -1200);
FORCEPROP 2 LAST CUSTOM_TXT_CDS <XR_PAGE_TITLE>
J 0
(-15670 10150);
DISPLAY 0.638298 (-15670 10150);
PAINT PINK (-15670 10150);
FORCEPROP 1 LAST CUSTOM_TXT_CDS <DOCNO>
J 0
(-2150 -815);
DISPLAY 0.978723 (-2150 -815);
FORCEPROP 1 LAST CUSTOM_TXT_CDS <CON_PAGE_NUM>
J 0
(-2255 -1150);
DISPLAY 0.978723 (-2255 -1150);
FORCEPROP 1 LAST CUSTOM_TXT_CDS <DATE>
J 0
(-800 -1025);
DISPLAY 0.978723 (-800 -1025);
FORCEPROP 1 LAST CUSTOM_TXT_CDS <TITLE>
J 1
(-1885 -570);
DISPLAY 0.978723 (-1885 -570);
FORCEPROP 1 LAST CUSTOM_TXT_CDS <DESIGNER>
J 0
(-800 -600);
DISPLAY 0.978723 (-800 -600);
FORCEPROP 1 LAST CUSTOM_TXT_CDS <CON_TOTAL_PAGES>
J 0
(-1945 -1150);
DISPLAY 0.808511 (-1945 -1150);
FORCEPROP 1 LAST CUSTOM_TXT_CDS <ASSY_PN>
J 0
(-2150 -1025);
DISPLAY 0.978723 (-2150 -1025);
FORCEPROP 1 LAST CUSTOM_TXT_CDS <DOCREV>
J 0
(-800 -825);
DISPLAY 0.978723 (-800 -825);
FORCEPROP 1 LAST TITLE CLOCK_GENERATOR
J 0
(-2600 -300);
DISPLAY 3.042553 (-2600 -300);
PAINT GREEN (-2600 -300);
FORCEPROP 1 LAST COMMENT_BODY TRUE
J 0
(-90 -1145);
DISPLAY 0.808511 (-90 -1145);
DISPLAY INVISIBLE (-90 -1145);
FORCEPROP 2 LAST CDS_LIB cls
J 0
(-100 -1200);
DISPLAY INVISIBLE (-100 -1200);
FORCEPROP 1 LAST CDS_LMAN_SYM_OUTLINE -15850,11500,200,-200
J 0
(-100 -1200);
DISPLAY 0.468085 (-100 -1200);
PAINT GREEN (-100 -1200);
DISPLAY INVISIBLE (-100 -1200);
FORCEPROP 2 LAST PAGE_BORDER TRUE
J 0
(-15670 10150);
DISPLAY 0.638298 (-15670 10150);
PAINT PINK (-15670 10150);
DISPLAY INVISIBLE (-15670 10150);
FORCEPROP 2 LAST CDS_XR_PAGE_TITLE CR-15 : @TIMECARD_LIB.TIMECARD(SCH_1):PAGE15
J 0
(-15670 10150);
DISPLAY 0.638298 (-15670 10150);
PAINT PINK (-15670 10150);
DISPLAY INVISIBLE (-15670 10150);
WIRE 16 -1 (-7950 6350)(-8050 6350);
WIRE 16 -1 (-7950 6350)(-7950 6000);
WIRE 16 -1 (-7950 2800)(-8050 2800);
WIRE 16 -1 (-7950 2800)(-7950 2450);
WIRE 16 -1 (-11900 6650)(-11650 6650);
WIRE 16 -1 (-11900 6650)(-11900 6800);
WIRE 16 -1 (-11350 6650)(-11650 6650);
WIRE 16 -1 (-11650 6450)(-11650 6650);
WIRE 16 -1 (-11900 3100)(-11650 3100);
WIRE 16 -1 (-11900 3100)(-11900 3250);
WIRE 16 -1 (-11350 3100)(-11650 3100);
WIRE 16 -1 (-11650 2900)(-11650 3100);
WIRE 16 -1 (-6650 2250)(-7000 2250);
WIRE 16 -1 (-6650 2450)(-6650 2250);
WIRE 16 -1 (-7000 2450)(-7000 2250);
WIRE 16 -1 (-7000 2250)(-7000 2200);
WIRE 16 -1 (-6650 5800)(-7000 5800);
WIRE 16 -1 (-6650 6000)(-6650 5800);
WIRE 16 -1 (-7000 6000)(-7000 5800);
WIRE 16 -1 (-7000 5800)(-7000 5750);
WIRE 16 -1 (-11650 2650)(-11650 2400);
WIRE 16 -1 (-11650 2400)(-10650 2400);
WIRE 16 -1 (-10200 2400)(-10650 2400);
WIRE 16 -1 (-10650 2650)(-10650 2400);
WIRE 16 -1 (-10200 2670)(-10200 2400);
WIRE 16 -1 (-10200 2300)(-10200 2400);
WIRE 16 -1 (-11650 6200)(-11650 5950);
WIRE 16 -1 (-11650 5950)(-10650 5950);
WIRE 16 -1 (-10200 5950)(-10650 5950);
WIRE 16 -1 (-10650 6200)(-10650 5950);
WIRE 16 -1 (-10200 6200)(-10200 5950);
WIRE 16 -1 (-10200 5850)(-10200 5950);
WIRE 16 -1 (-9650 6150)(-9000 6150);
WIRE 16 -1 (-9000 6450)(-9000 6150);
WIRE 16 -1 (-8850 6450)(-9000 6450);
WIRE 16 -1 (-9000 6450)(-9250 6450);
WIRE 16 273 (-14850 4700)(-800 4700);
WIRE 16 -1 (-9200 2900)(-9000 2900);
WIRE 16 -1 (-9000 2900)(-8850 2900);
WIRE 16 -1 (-9000 2900)(-9000 2600);
WIRE 16 -1 (-9650 2600)(-9000 2600);
WIRE 16 -1 (-10650 6650)(-10200 6650);
WIRE 16 -1 (-10650 6450)(-10650 6650);
WIRE 16 -1 (-10650 6650)(-10950 6650);
WIRE 16 -1 (-10200 6650)(-9800 6650);
WIRE 16 -1 (-10200 6450)(-10200 6650);
WIRE 16 -1 (-8850 6650)(-9800 6650);
FORCEPROP 2 LAST SIG_NAME VDD3V3_OSC_200M
J 0
(-9760 6660);
DISPLAY 1.021277 (-9760 6660);
WIRE 16 -1 (-9800 6450)(-9800 6650);
WIRE 16 -1 (-9500 6450)(-9800 6450);
WIRE 16 -1 (-6650 6650)(-6250 6650);
WIRE 16 -1 (-6650 6650)(-6650 6250);
WIRE 16 -1 (-8050 6650)(-6650 6650);
FORCEPROP 2 LAST SIG_NAME OSC_200M_CLKP
J 0
(-7810 6660);
DISPLAY 1.021277 (-7810 6660);
WIRE 16 -1 (-6000 6650)(-4150 6650);
FORCEPROP 2 LAST SIG_NAME MHZ200CLKP_CLKIN
J 0
(-4960 6660);
DISPLAY 1.021277 (-4960 6660);
WIRE 16 -1 (-7000 6250)(-7000 6550);
WIRE 16 -1 (-7000 6550)(-6250 6550);
WIRE 16 -1 (-8050 6550)(-7000 6550);
FORCEPROP 2 LAST SIG_NAME OSC_200M_CLKN
J 0
(-7810 6560);
DISPLAY 1.021277 (-7810 6560);
WIRE 16 -1 (-6000 6550)(-4150 6550);
FORCEPROP 2 LAST SIG_NAME MHZ200CLKN_CLKIN
J 0
(-4960 6560);
DISPLAY 1.021277 (-4960 6560);
WIRE 16 273 (-4750 1950)(-4750 2800);
WIRE 16 273 (-7450 1950)(-4750 1950);
WIRE 16 273 (-4750 2800)(-7450 2800);
WIRE 16 273 (-7450 2800)(-7450 1950);
WIRE 16 -1 (-6650 3100)(-6300 3100);
WIRE 16 -1 (-6650 3100)(-6650 2700);
WIRE 16 -1 (-8050 3100)(-6650 3100);
FORCEPROP 2 LAST SIG_NAME OSC_125M_CLKP
J 0
(-7810 3110);
DISPLAY 1.021277 (-7810 3110);
WIRE 16 -1 (-7000 2700)(-7000 3000);
WIRE 16 -1 (-7000 3000)(-6300 3000);
WIRE 16 -1 (-8050 3000)(-7000 3000);
FORCEPROP 2 LAST SIG_NAME OSC_125M_CLKN
J 0
(-7810 3010);
DISPLAY 1.021277 (-7810 3010);
WIRE 16 -1 (-4300 3100)(-6050 3100);
FORCEPROP 2 LAST SIG_NAME MHZ125CLKP_CLKIN
J 0
(-5110 3110);
DISPLAY 1.021277 (-5110 3110);
WIRE 16 -1 (-4300 3000)(-6050 3000);
FORCEPROP 2 LAST SIG_NAME MHZ125CLKN_CLKIN
J 0
(-5110 3010);
DISPLAY 1.021277 (-5110 3010);
WIRE 16 273 (-4750 5550)(-4750 6350);
WIRE 16 273 (-7400 5550)(-4750 5550);
WIRE 16 273 (-4750 6350)(-7400 6350);
WIRE 16 273 (-7400 6350)(-7400 5550);
WIRE 16 -1 (-10650 2900)(-10650 3100);
WIRE 16 -1 (-10650 3100)(-10200 3100);
WIRE 16 -1 (-10650 3100)(-10950 3100);
WIRE 16 -1 (-9800 3100)(-10200 3100);
WIRE 16 -1 (-10200 2920)(-10200 3100);
WIRE 16 -1 (-8850 3100)(-9800 3100);
FORCEPROP 2 LAST SIG_NAME VDD3V3_OSC_125M
J 0
(-9710 3110);
DISPLAY 1.021277 (-9710 3110);
WIRE 16 -1 (-9800 2900)(-9800 3100);
WIRE 16 -1 (-9450 2900)(-9800 2900);
DOT 1 (-10650 2400);
DOT 1 (-9000 2900);
DOT 1 (-9000 6450);
DOT 1 (-9800 3100);
DOT 1 (-10200 3100);
DOT 1 (-10200 2400);
DOT 1 (-10650 3100);
DOT 1 (-11650 3100);
DOT 1 (-9800 6650);
DOT 1 (-10650 6650);
DOT 1 (-7000 2250);
DOT 1 (-7000 3000);
DOT 1 (-6650 3100);
DOT 1 (-11650 6650);
DOT 1 (-10650 5950);
DOT 1 (-10200 5950);
DOT 1 (-10200 6650);
DOT 1 (-7000 5800);
DOT 1 (-7000 6550);
DOT 1 (-6650 6650);
FORCENOTE
RESERVED FOR LVPECL & HCSL OUTPUT FORMAT
(-6800 5650) 0;
DISPLAY LEFT (-6800 5650);
DISPLAY 1.021277 (-6800 5650);
FORCENOTE
HCSL: R =50 OHM
(-6250 5850) 0;
DISPLAY LEFT (-6250 5850);
DISPLAY 1.021277 (-6250 5850);
FORCENOTE
CLOCK GENERATOR: 125MHZ.
(-8750 3650) 0;
DISPLAY LEFT (-8750 3650);
DISPLAY 3.148936 (-8750 3650);
FORCENOTE
CLOCK GENERATOR: 200MHZ.
(-8750 7250) 0;
DISPLAY LEFT (-8750 7250);
DISPLAY 3.148936 (-8750 7250);
FORCENOTE
LVPECL: R =150 OHM
(-6350 2400) 0;
DISPLAY LEFT (-6350 2400);
DISPLAY 1.021277 (-6350 2400);
FORCENOTE
HCSL: R =50 OHM
(-6250 2300) 0;
DISPLAY LEFT (-6250 2300);
DISPLAY 1.021277 (-6250 2300);
FORCENOTE
RESERVED FOR LVPECL & HCSL OUTPUT FORMAT
(-6800 2100) 0;
DISPLAY LEFT (-6800 2100);
DISPLAY 1.021277 (-6800 2100);
FORCENOTE
LVDS
(-3900 3050) 0;
DISPLAY LEFT (-3900 3050);
DISPLAY 1.276596 (-3900 3050);
FORCENOTE
125MHZ
(-8550 2900) 0;
DISPLAY LEFT (-8550 2900);
DISPLAY 1.021277 (-8550 2900);
FORCENOTE
200MHZ
(-8550 6450) 0;
DISPLAY LEFT (-8550 6450);
DISPLAY 1.021277 (-8550 6450);
FORCENOTE
LVPECL: R =150 OHM
(-6350 5950) 0;
DISPLAY LEFT (-6350 5950);
DISPLAY 1.021277 (-6350 5950);
FORCENOTE
LVDS
(-3700 6600) 0;
DISPLAY LEFT (-3700 6600);
DISPLAY 1.276596 (-3700 6600);
FORCENOTE
CLOCK_GENERATOR
(-9650 9050) 0;
DISPLAY LEFT (-9650 9050);
DISPLAY 4.914894 (-9650 9050);
QUIT
